(kicad_pcb
	(version 20241229)
	(generator "pcbnew")
	(generator_version "9.0")
	(general
		(thickness 1.552)
		(legacy_teardrops no)
	)
	(paper "A4")
	(title_block
		(date "2023-07-25")
		(rev "1.1.4")
		(comment 9 "footprint 14 of 379 (U11), pads 82-165 of 256")
	)
	(layers
		(0 "F.Cu" signal)
		(4 "In1.Cu" signal)
		(6 "In2.Cu" signal)
		(8 "In3.Cu" signal)
		(10 "In4.Cu" signal)
		(12 "In5.Cu" signal)
		(14 "In6.Cu" signal)
		(2 "B.Cu" signal)
		(9 "F.Adhes" user "F.Adhesive")
		(11 "B.Adhes" user "B.Adhesive")
		(13 "F.Paste" user)
		(15 "B.Paste" user)
		(5 "F.SilkS" user "F.Silkscreen")
		(7 "B.SilkS" user "B.Silkscreen")
		(1 "F.Mask" user)
		(3 "B.Mask" user)
		(17 "Dwgs.User" user "User.Drawings")
		(19 "Cmts.User" user "User.Comments")
		(21 "Eco1.User" user "User.Eco1")
		(23 "Eco2.User" user "User.Eco2")
		(25 "Edge.Cuts" user)
		(27 "Margin" user)
		(31 "F.CrtYd" user "F.Courtyard")
		(29 "B.CrtYd" user "B.Courtyard")
		(35 "F.Fab" user)
		(33 "B.Fab" user)
	)
	(footprint "antmicro-footprints:BGA-256_14x14mm_Layout16x16_P0.8mm"
		(locked yes)
		(layer "F.Cu")
		(at 126.3 90.3 180)
		(property "Reference" "U11"
			(at 0 -8 180)
			(layer "F.SilkS")
			(effects
				(font
					(size 0.7 0.7)
					(thickness 0.15)
				)
				(justify left bottom)
			)
		)
		(property "Value" "LIFCL-40-9BG256C"
			(at -8 8.55 180)
			(layer "F.Fab")
			(effects
				(font
					(size 0.7 0.7)
					(thickness 0.15)
				)
				(justify left bottom)
			)
		)
		(property "Datasheet" "https://www.latticesemi.com/-/media/LatticeSemi/Documents/DataSheets/CrossLink/FPGA-DS-02007-2-1-CrossLink-Family-Data-Sheet.ashx?document_id=51662"
			(at 0 0 180)
			(layer "F.Fab")
			(hide yes)
			(effects
				(font
					(size 1.27 1.27)
					(thickness 0.15)
				)
			)
		)
		(property "Description" "CrossLink-NX™ Field Programmable Gate Array 256-LFBGA"
			(at 0 0 180)
			(layer "F.Fab")
			(hide yes)
			(effects
				(font
					(size 1.27 1.27)
					(thickness 0.15)
				)
			)
		)
		(property "Author" "Antmicro"
			(at 252.6 180.6 0)
			(layer "F.Fab")
			(hide yes)
			(effects
				(font
					(size 1 1)
					(thickness 0.15)
				)
			)
		)
		(property "License" "Apache-2.0"
			(at 252.6 180.6 0)
			(layer "F.Fab")
			(hide yes)
			(effects
				(font
					(size 1 1)
					(thickness 0.15)
				)
			)
		)
		(property "MPN" "LIFCL-40-9BG256C"
			(at 252.6 180.6 0)
			(layer "F.Fab")
			(hide yes)
			(effects
				(font
					(size 1 1)
					(thickness 0.15)
				)
			)
		)
		(property "Manufacturer" "Lattice Semiconductor"
			(at 252.6 180.6 0)
			(layer "F.Fab")
			(hide yes)
			(effects
				(font
					(size 1 1)
					(thickness 0.15)
				)
			)
		)
		(sheetname "/DDR3/")
		(sheetfile "ddr3.kicad_sch")
		(attr smd)
		(pad "F2" smd circle
			(at -5.2 -2 180)
			(size 0.45 0.45)
			(layers "F.Cu" "F.Mask" "F.Paste")
			(net 70 "/Peripherals/MIPI0_D2_N")
			(pinfunction "DPHY0_D2-")
			(pintype "bidirectional")
		)
		(pad "F3" smd circle
			(at -4.4 -2 180)
			(size 0.45 0.45)
			(layers "F.Cu" "F.Mask" "F.Paste")
			(net 1 "GND")
			(pinfunction "VSSADPHY")
			(pintype "passive")
		)
		(pad "F4" smd circle
			(at -3.6 -2 180)
			(size 0.45 0.45)
			(layers "F.Cu" "F.Mask" "F.Paste")
			(net 181 "/SDI/SDOUT_TDO")
			(pinfunction "PL19A/PCLKT7_1")
			(pintype "bidirectional")
		)
		(pad "F5" smd circle
			(at -2.8 -2 180)
			(size 0.45 0.45)
			(layers "F.Cu" "F.Mask" "F.Paste")
			(net 2 "+3V3")
			(pinfunction "VCCIO7")
			(pintype "power_in")
		)
		(pad "F6" smd circle
			(at -2 -2 180)
			(size 0.45 0.45)
			(layers "F.Cu" "F.Mask" "F.Paste")
			(net 176 "/SDI/STANDBY")
			(pinfunction "PL17A/PCLKT7_2")
			(pintype "bidirectional")
		)
		(pad "F7" smd circle
			(at -1.2 -2 180)
			(size 0.45 0.45)
			(layers "F.Cu" "F.Mask" "F.Paste")
			(net 10 "/FPGA Power/VCC_AUXA")
			(pinfunction "VCCAUXA")
			(pintype "power_in")
		)
		(pad "F8" smd circle
			(at -0.4 -2 180)
			(size 0.45 0.45)
			(layers "F.Cu" "F.Mask" "F.Paste")
			(net 9 "/FPGA Power/VCC_AUX")
			(pinfunction "VCCAUX")
			(pintype "power_in")
		)
		(pad "F9" smd circle
			(at 0.4 -2 180)
			(size 0.45 0.45)
			(layers "F.Cu" "F.Mask" "F.Paste")
			(net 108 "/Peripherals/FFC2_VSYNC0")
			(pinfunction "PR3B")
			(pintype "bidirectional")
		)
		(pad "F10" smd circle
			(at 1.2 -2 180)
			(size 0.45 0.45)
			(layers "F.Cu" "F.Mask" "F.Paste")
			(net 89 "/Peripherals/FFC1_RESET")
			(pinfunction "PR8A")
			(pintype "bidirectional")
		)
		(pad "F11" smd circle
			(at 2 -2 180)
			(size 0.45 0.45)
			(layers "F.Cu" "F.Mask" "F.Paste")
			(net 172 "TDI")
			(pinfunction "PR8B/TDI/SSI")
			(pintype "bidirectional")
		)
		(pad "F12" smd circle
			(at 2.8 -2 180)
			(size 0.45 0.45)
			(layers "F.Cu" "F.Mask" "F.Paste")
			(net 1 "GND")
			(pinfunction "VSS")
			(pintype "passive")
		)
		(pad "F13" smd circle
			(at 3.6 -2 180)
			(size 0.45 0.45)
			(layers "F.Cu" "F.Mask" "F.Paste")
			(net 2 "+3V3")
			(pinfunction "VCCIO1")
			(pintype "power_in")
		)
		(pad "F14" smd circle
			(at 4.4 -2 180)
			(size 0.45 0.45)
			(layers "F.Cu" "F.Mask" "F.Paste")
			(net 170 "TCK")
			(pinfunction "PR13A/TCK/SCLK")
			(pintype "bidirectional")
		)
		(pad "F15" smd circle
			(at 5.2 -2 180)
			(size 0.45 0.45)
			(layers "F.Cu" "F.Mask" "F.Paste")
			(net 44 "DIP0")
			(pinfunction "PR13B")
			(pintype "bidirectional")
		)
		(pad "F16" smd circle
			(at 6 -2 180)
			(size 0.45 0.45)
			(layers "F.Cu" "F.Mask" "F.Paste")
			(net 88 "/Peripherals/FFC1_VSYNC0")
			(pinfunction "PR19A/PCLKT1_1")
			(pintype "bidirectional")
		)
		(pad "G1" smd circle
			(at -6 -1.2 180)
			(size 0.45 0.45)
			(layers "F.Cu" "F.Mask" "F.Paste")
			(net 1 "GND")
			(pinfunction "VSSADPHY")
			(pintype "passive")
		)
		(pad "G2" smd circle
			(at -5.2 -1.2 180)
			(size 0.45 0.45)
			(layers "F.Cu" "F.Mask" "F.Paste")
			(net 1 "GND")
			(pinfunction "VSS")
			(pintype "passive")
		)
		(pad "G3" smd circle
			(at -4.4 -1.2 180)
			(size 0.45 0.45)
			(layers "F.Cu" "F.Mask" "F.Paste")
			(net 183 "/SDI/SDI_STAT5")
			(pinfunction "PL20A/PCLKT7_0")
			(pintype "bidirectional")
		)
		(pad "G4" smd circle
			(at -3.6 -1.2 180)
			(size 0.45 0.45)
			(layers "F.Cu" "F.Mask" "F.Paste")
			(net 184 "/SDI/~{SDO_DISABLE}")
			(pinfunction "PL19B")
			(pintype "bidirectional")
		)
		(pad "G5" smd circle
			(at -2.8 -1.2 180)
			(size 0.45 0.45)
			(layers "F.Cu" "F.Mask" "F.Paste")
			(net 1 "GND")
			(pinfunction "VSS")
			(pintype "passive")
		)
		(pad "G6" smd circle
			(at -2 -1.2 180)
			(size 0.45 0.45)
			(layers "F.Cu" "F.Mask" "F.Paste")
			(net 185 "/SDI/SDO_EN{slash}DIS")
			(pinfunction "PL17B")
			(pintype "bidirectional")
		)
		(pad "G7" smd circle
			(at -1.2 -1.2 180)
			(size 0.45 0.45)
			(layers "F.Cu" "F.Mask" "F.Paste")
			(net 9 "/FPGA Power/VCC_AUX")
			(pinfunction "VCCAUX")
			(pintype "passive")
		)
		(pad "G8" smd circle
			(at -0.4 -1.2 180)
			(size 0.45 0.45)
			(layers "F.Cu" "F.Mask" "F.Paste")
			(net 1 "GND")
			(pinfunction "VSS")
			(pintype "passive")
		)
		(pad "G9" smd circle
			(at 0.4 -1.2 180)
			(size 0.45 0.45)
			(layers "F.Cu" "F.Mask" "F.Paste")
			(net 101 "SDA")
			(pinfunction "PR11A/SDA/USER_SDA")
			(pintype "bidirectional")
		)
		(pad "G10" smd circle
			(at 1.2 -1.2 180)
			(size 0.45 0.45)
			(layers "F.Cu" "F.Mask" "F.Paste")
			(net 100 "SCL")
			(pinfunction "PR11B/SCL/USER_SCL")
			(pintype "bidirectional")
		)
		(pad "G11" smd circle
			(at 2 -1.2 180)
			(size 0.45 0.45)
			(layers "F.Cu" "F.Mask" "F.Paste")
			(net 91 "/Peripherals/FCC1_SDA1")
			(pinfunction "PR15A")
			(pintype "bidirectional")
		)
		(pad "G12" smd circle
			(at 2.8 -1.2 180)
			(size 0.45 0.45)
			(layers "F.Cu" "F.Mask" "F.Paste")
			(net 92 "/Peripherals/FCC1_SCL1")
			(pinfunction "PR15B")
			(pintype "bidirectional")
		)
		(pad "G13" smd circle
			(at 3.6 -1.2 180)
			(size 0.45 0.45)
			(layers "F.Cu" "F.Mask" "F.Paste")
			(net 93 "/Peripherals/FCC1_SDA2")
			(pinfunction "PR17A/PCLKT1_2")
			(pintype "bidirectional")
		)
		(pad "G14" smd circle
			(at 4.4 -1.2 180)
			(size 0.45 0.45)
			(layers "F.Cu" "F.Mask" "F.Paste")
			(net 94 "/Peripherals/FCC1_SCL2")
			(pinfunction "PR17B")
			(pintype "bidirectional")
		)
		(pad "G15" smd circle
			(at 5.2 -1.2 180)
			(size 0.45 0.45)
			(layers "F.Cu" "F.Mask" "F.Paste")
			(net 186 "40MHz_3V3")
			(pinfunction "PR20A/PCLKT1_0\n")
			(pintype "bidirectional")
		)
		(pad "G16" smd circle
			(at 6 -1.2 180)
			(size 0.45 0.45)
			(layers "F.Cu" "F.Mask" "F.Paste")
			(net 90 "/Peripherals/FFC1_VSYNC1")
			(pinfunction "PR19B")
			(pintype "bidirectional")
		)
		(pad "H1" smd circle
			(at -6 -0.4 180)
			(size 0.45 0.45)
			(layers "F.Cu" "F.Mask" "F.Paste")
			(net 194 "/SDI/SDI_D7")
			(pinfunction "PL27A")
			(pintype "bidirectional")
		)
		(pad "H2" smd circle
			(at -5.2 -0.4 180)
			(size 0.45 0.45)
			(layers "F.Cu" "F.Mask" "F.Paste")
			(net 205 "/SDI/SDI_D11")
			(pinfunction "PL27B")
			(pintype "bidirectional")
		)
		(pad "H3" smd circle
			(at -4.4 -0.4 180)
			(size 0.45 0.45)
			(layers "F.Cu" "F.Mask" "F.Paste")
			(net 180 "/SDI/TIM_861")
			(pinfunction "PL26B")
			(pintype "bidirectional")
		)
		(pad "H4" smd circle
			(at -3.6 -0.4 180)
			(size 0.45 0.45)
			(layers "F.Cu" "F.Mask" "F.Paste")
			(net 195 "/SDI/SDI_D8")
			(pinfunction "PL26A")
			(pintype "bidirectional")
		)
		(pad "H5" smd circle
			(at -2.8 -0.4 180)
			(size 0.45 0.45)
			(layers "F.Cu" "F.Mask" "F.Paste")
			(net 203 "/SDI/SDI_D10")
			(pinfunction "PL24B")
			(pintype "bidirectional")
		)
		(pad "H6" smd circle
			(at -2 -0.4 180)
			(size 0.45 0.45)
			(layers "F.Cu" "F.Mask" "F.Paste")
			(net 182 "/SDI/SDIN_TDI")
			(pinfunction "PL24A")
			(pintype "bidirectional")
		)
		(pad "H7" smd circle
			(at -1.2 -0.4 180)
			(size 0.45 0.45)
			(layers "F.Cu" "F.Mask" "F.Paste")
			(net 4 "1V0_Power")
			(pinfunction "VCC")
			(pintype "passive")
		)
		(pad "H8" smd circle
			(at -0.4 -0.4 180)
			(size 0.45 0.45)
			(layers "F.Cu" "F.Mask" "F.Paste")
			(net 1 "GND")
			(pinfunction "VSS")
			(pintype "passive")
		)
		(pad "H9" smd circle
			(at 0.4 -0.4 180)
			(size 0.45 0.45)
			(layers "F.Cu" "F.Mask" "F.Paste")
			(net 1 "GND")
			(pinfunction "VSS")
			(pintype "passive")
		)
		(pad "H10" smd circle
			(at 1.2 -0.4 180)
			(size 0.45 0.45)
			(layers "F.Cu" "F.Mask" "F.Paste")
			(net 43 "DIP1")
			(pinfunction "PR30B")
			(pintype "bidirectional")
		)
		(pad "H11" smd circle
			(at 2 -0.4 180)
			(size 0.45 0.45)
			(layers "F.Cu" "F.Mask" "F.Paste")
			(net 193 "/SDI/DVB_ASI")
			(pinfunction "PR30A/PCLKT2_0")
			(pintype "bidirectional")
		)
		(pad "H12" smd circle
			(at 2.8 -0.4 180)
			(size 0.45 0.45)
			(layers "F.Cu" "F.Mask" "F.Paste")
			(net 371 "FCC2_SCL2")
			(pinfunction "PR32B")
			(pintype "bidirectional")
		)
		(pad "H13" smd circle
			(at 3.6 -0.4 180)
			(size 0.45 0.45)
			(layers "F.Cu" "F.Mask" "F.Paste")
			(net 199 "/SDI/IOPROC_EN{slash}~{DIS}")
			(pinfunction "PR32A/PCLKT2_1")
			(pintype "bidirectional")
		)
		(pad "H14" smd circle
			(at 4.4 -0.4 180)
			(size 0.45 0.45)
			(layers "F.Cu" "F.Mask" "F.Paste")
			(net 333 "GPIO1")
			(pinfunction "PR27B")
			(pintype "bidirectional")
		)
		(pad "H15" smd circle
			(at 5.2 -0.4 180)
			(size 0.45 0.45)
			(layers "F.Cu" "F.Mask" "F.Paste")
			(net 334 "GPIO2")
			(pinfunction "PR27A")
			(pintype "bidirectional")
		)
		(pad "H16" smd circle
			(at 6 -0.4 180)
			(size 0.45 0.45)
			(layers "F.Cu" "F.Mask" "F.Paste")
			(net 332 "GPIO0")
			(pinfunction "PR26A")
			(pintype "bidirectional")
		)
		(pad "J1" smd circle
			(at -6 0.4 180)
			(size 0.45 0.45)
			(layers "F.Cu" "F.Mask" "F.Paste")
			(net 187 "/SDI/SDI_D4")
			(pinfunction "PL32A/PCLKT6_1")
			(pintype "bidirectional")
		)
		(pad "J2" smd circle
			(at -5.2 0.4 180)
			(size 0.45 0.45)
			(layers "F.Cu" "F.Mask" "F.Paste")
			(net 188 "/SDI/SDI_D5")
			(pinfunction "PL32B")
			(pintype "bidirectional")
		)
		(pad "J3" smd circle
			(at -4.4 0.4 180)
			(size 0.45 0.45)
			(layers "F.Cu" "F.Mask" "F.Paste")
			(net 1 "GND")
			(pinfunction "VSS")
			(pintype "passive")
		)
		(pad "J4" smd circle
			(at -3.6 0.4 180)
			(size 0.45 0.45)
			(layers "F.Cu" "F.Mask" "F.Paste")
			(net 2 "+3V3")
			(pinfunction "VCCIO6")
			(pintype "power_in")
		)
		(pad "J5" smd circle
			(at -2.8 0.4 180)
			(size 0.45 0.45)
			(layers "F.Cu" "F.Mask" "F.Paste")
			(net 210 "/SDI/SDI_D15")
			(pinfunction "PL30B")
			(pintype "bidirectional")
		)
		(pad "J6" smd circle
			(at -2 0.4 180)
			(size 0.45 0.45)
			(layers "F.Cu" "F.Mask" "F.Paste")
			(net 204 "/SDI/SDI_D12")
			(pinfunction "PL30A/PCLKT6_0")
			(pintype "bidirectional")
		)
		(pad "J7" smd circle
			(at -1.2 0.4 180)
			(size 0.45 0.45)
			(layers "F.Cu" "F.Mask" "F.Paste")
			(net 1 "GND")
			(pinfunction "VSS")
			(pintype "passive")
		)
		(pad "J8" smd circle
			(at -0.4 0.4 180)
			(size 0.45 0.45)
			(layers "F.Cu" "F.Mask" "F.Paste")
			(net 1 "GND")
			(pinfunction "VSS")
			(pintype "passive")
		)
		(pad "J9" smd circle
			(at 0.4 0.4 180)
			(size 0.45 0.45)
			(layers "F.Cu" "F.Mask" "F.Paste")
			(net 1 "GND")
			(pinfunction "VSS")
			(pintype "passive")
		)
		(pad "J10" smd circle
			(at 1.2 0.4 180)
			(size 0.45 0.45)
			(layers "F.Cu" "F.Mask" "F.Paste")
			(net 4 "1V0_Power")
			(pinfunction "VCC")
			(pintype "passive")
		)
		(pad "J11" smd circle
			(at 2 0.4 180)
			(size 0.45 0.45)
			(layers "F.Cu" "F.Mask" "F.Paste")
			(net 357 "TXD")
			(pinfunction "PR36A")
			(pintype "bidirectional")
		)
		(pad "J12" smd circle
			(at 2.8 0.4 180)
			(size 0.45 0.45)
			(layers "F.Cu" "F.Mask" "F.Paste")
			(net 355 "RXD")
			(pinfunction "PR36B")
			(pintype "bidirectional")
		)
		(pad "J13" smd circle
			(at 3.6 0.4 180)
			(size 0.45 0.45)
			(layers "F.Cu" "F.Mask" "F.Paste")
			(net 2 "+3V3")
			(pinfunction "VCCIO2")
			(pintype "power_in")
		)
		(pad "J14" smd circle
			(at 4.4 0.4 180)
			(size 0.45 0.45)
			(layers "F.Cu" "F.Mask" "F.Paste")
			(net 1 "GND")
			(pinfunction "VSS")
			(pintype "passive")
		)
		(pad "J15" smd circle
			(at 5.2 0.4 180)
			(size 0.45 0.45)
			(layers "F.Cu" "F.Mask" "F.Paste")
			(net 335 "GPIO3")
			(pinfunction "PR34B")
			(pintype "bidirectional")
		)
		(pad "J16" smd circle
			(at 6 0.4 180)
			(size 0.45 0.45)
			(layers "F.Cu" "F.Mask" "F.Paste")
			(net 201 "/SDI/~{SMPTE_BYPASS}")
			(pinfunction "PR34A/PCLKT2_2")
			(pintype "bidirectional")
		)
		(pad "K1" smd circle
			(at -6 1.2 180)
			(size 0.45 0.45)
			(layers "F.Cu" "F.Mask" "F.Paste")
			(net 190 "/SDI/SDI_D2")
			(pinfunction "PL34A/PCLKT6_2")
			(pintype "bidirectional")
		)
		(pad "K2" smd circle
			(at -5.2 1.2 180)
			(size 0.45 0.45)
			(layers "F.Cu" "F.Mask" "F.Paste")
			(net 189 "/SDI/SDI_D3")
			(pinfunction "PL34B")
			(pintype "bidirectional")
		)
		(pad "K3" smd circle
			(at -4.4 1.2 180)
			(size 0.45 0.45)
			(layers "F.Cu" "F.Mask" "F.Paste")
			(net 202 "/SDI/SDI_D9")
			(pinfunction "PL36B")
			(pintype "bidirectional")
		)
		(pad "K4" smd circle
			(at -3.6 1.2 180)
			(size 0.45 0.45)
			(layers "F.Cu" "F.Mask" "F.Paste")
			(net 213 "/SDI/SDI_D19")
			(pinfunction "PL36A")
			(pintype "bidirectional")
		)
		(pad "K5" smd circle
			(at -2.8 1.2 180)
			(size 0.45 0.45)
			(layers "F.Cu" "F.Mask" "F.Paste")
			(net 207 "/SDI/SDI_D13")
			(pinfunction "PL38B")
			(pintype "bidirectional")
		)
		(pad "K6" smd circle
			(at -2 1.2 180)
			(size 0.45 0.45)
			(layers "F.Cu" "F.Mask" "F.Paste")
			(net 216 "/SDI/SDI_D18")
			(pinfunction "PL38A")
			(pintype "bidirectional")
		)
		(pad "K7" smd circle
			(at -1.2 1.2 180)
			(size 0.45 0.45)
			(layers "F.Cu" "F.Mask" "F.Paste")
			(net 78 "/Peripherals/MIPI2_D3_N")
			(pinfunction "PB10B/PCLKC5_2/ADC_CN2/COMP3N")
			(pintype "bidirectional")
		)
		(pad "K8" smd circle
			(at -0.4 1.2 180)
			(size 0.45 0.45)
			(layers "F.Cu" "F.Mask" "F.Paste")
			(net 9 "/FPGA Power/VCC_AUX")
			(pinfunction "VCCAUXH4")
			(pintype "power_in")
		)
		(pad "K9" smd circle
			(at 0.4 1.2 180)
			(size 0.45 0.45)
			(layers "F.Cu" "F.Mask" "F.Paste")
			(net 4 "1V0_Power")
			(pinfunction "VCCECLK")
			(pintype "power_in")
		)
		(pad "K10" smd circle
			(at 1.2 1.2 180)
			(size 0.45 0.45)
			(layers "F.Cu" "F.Mask" "F.Paste")
			(net 9 "/FPGA Power/VCC_AUX")
			(pinfunction "VCCAUXH3")
			(pintype "power_in")
		)
		(pad "K11" smd circle
			(at 2 1.2 180)
			(size 0.45 0.45)
			(layers "F.Cu" "F.Mask" "F.Paste")
			(net 208 "/SDI/JTAG{slash}~{HOST}")
			(pinfunction "PR38A")
			(pintype "bidirectional")
		)
		(pad "K12" smd circle
			(at 2.8 1.2 180)
			(size 0.45 0.45)
			(layers "F.Cu" "F.Mask" "F.Paste")
			(net 209 "/SDI/~{RC_BYP}")
			(pinfunction "PR38B")
			(pintype "bidirectional")
		)
		(pad "K13" smd circle
			(at 3.6 1.2 180)
			(size 0.45 0.45)
			(layers "F.Cu" "F.Mask" "F.Paste")
			(net 1 "GND")
			(pinfunction "ADC_D0-")
			(pintype "passive")
		)
		(pad "K14" smd circle
			(at 4.4 1.2 180)
			(size 0.45 0.45)
			(layers "F.Cu" "F.Mask" "F.Paste")
			(net 1 "GND")
			(pinfunction "ADC_D0+")
			(pintype "passive")
		)
		(pad "K15" smd circle
			(at 5.2 1.2 180)
			(size 0.45 0.45)
			(layers "F.Cu" "F.Mask" "F.Paste")
			(net 1 "GND")
			(pinfunction "ADC_D1+")
			(pintype "passive")
		)
		(pad "K16" smd circle
			(at 6 1.2 180)
			(size 0.45 0.45)
			(layers "F.Cu" "F.Mask" "F.Paste")
			(net 1 "GND")
			(pinfunction "ADC_D1-")
			(pintype "passive")
		)
		(pad "L1" smd circle
			(at -6 2 180)
			(size 0.45 0.45)
			(layers "F.Cu" "F.Mask" "F.Paste")
			(net 192 "/SDI/SDI_D0")
			(pinfunction "PL40A")
			(pintype "bidirectional")
		)
		(pad "L2" smd circle
			(at -5.2 2 180)
			(size 0.45 0.45)
			(layers "F.Cu" "F.Mask" "F.Paste")
			(net 191 "/SDI/SDI_D1")
			(pinfunction "PL40B")
			(pintype "bidirectional")
		)
		(pad "L3" smd circle
			(at -4.4 2 180)
			(size 0.45 0.45)
			(layers "F.Cu" "F.Mask" "F.Paste")
			(net 196 "/SDI/SDI_D6")
			(pinfunction "PL47B")
			(pintype "bidirectional")
		)
		(pad "L4" smd circle
			(at -3.6 2 180)
			(size 0.45 0.45)
			(layers "F.Cu" "F.Mask" "F.Paste")
			(net 211 "/SDI/SDI_D16")
			(pinfunction "PL46A")
			(pintype "bidirectional")
		)
		(pad "L5" smd circle
			(at -2.8 2 180)
			(size 0.45 0.45)
			(layers "F.Cu" "F.Mask" "F.Paste")
			(net 197 "/SDI/SDI_PCLK")
			(pinfunction "PL46B")
			(pintype "bidirectional")
		)
	)
)
